# T6G (Grand Teton) — schematic netlist excerpt (pin names and nets, part order shuffled) for the footprints in the layout excerpt that follows; sources: Cadence DE-HDL packaged netlist, KiCad conversion of 04192023_DAF0TMB3IC0_F0TG_MB_C_brd_V02_OCP.brd

PC174  Q_CAP  560PF 50V 10% EMPTY  pkg C0402  page 222 : A = SW_PVDDIO_P1_SW1 ; B = SW_PVDDIO_P1_SW1_RC
C903  Q_CAP_DIFFBUS  DIFF BUS_0.22UF 6.3V 20% X6S  pkg C0201  page 63 : \1\ = P5E_CPU0_P0_TX_C_DP<15> ; \2\ = P5E_CPU0_P0_TX_DP<15>
R3679  Q_RES  0 5% EMPTY  pkg 0402LF  page 257 : A = P12V_AUX_ADC ; B = P12V_AUX_ADC_MAM

(kicad_pcb
	(version 20260206)
	(generator "pcbnew")
	(generator_version "10.0")
	(general
		(thickness 1.6)
		(legacy_teardrops no)
	)
	(paper "A4")
	(title_block
		(title "04192023_DAF0TMB3IC0_F0TG_MB_C_brd_V02_OCP.brd")
		(comment 1 "Grand Teton / footprints 3625-3627 of 8354")
	)
	(layers
		(0 "F.Cu" signal "TOP")
		(4 "In1.Cu" signal "GND")
		(6 "In2.Cu" signal "IN1")
		(8 "In3.Cu" signal "GND1")
		(10 "In4.Cu" signal "IN2")
		(12 "In5.Cu" signal "GND2")
		(14 "In6.Cu" signal "IN3")
		(16 "In7.Cu" signal "GND3")
		(18 "In8.Cu" signal "VCC")
		(20 "In9.Cu" signal "VCC1")
		(22 "In10.Cu" signal "GND4")
		(24 "In11.Cu" signal "IN4")
		(26 "In12.Cu" signal "GND5")
		(28 "In13.Cu" signal "IN5")
		(30 "In14.Cu" signal "GND6")
		(32 "In15.Cu" signal "IN6")
		(34 "In16.Cu" signal "GND7")
		(2 "B.Cu" signal "BOTTOM")
		(9 "F.Adhes" user "F.Adhesive")
		(11 "B.Adhes" user "B.Adhesive")
		(13 "F.Paste" user "Package Geometry/Pastemask Top")
		(15 "B.Paste" user "Package Geometry/Pastemask Bottom")
		(5 "F.SilkS" user "Ref Des/Silkscreen Top")
		(7 "B.SilkS" user "Ref Des/Silkscreen Bottom")
		(1 "F.Mask" user "Board Geometry/Soldermask Top")
		(3 "B.Mask" user "Board Geometry/Soldermask Bottom")
		(17 "Dwgs.User" user "User.Drawings")
		(19 "Cmts.User" user "User.Comments")
		(21 "Eco1.User" user "User.Eco1")
		(23 "Eco2.User" user "User.Eco2")
		(25 "Edge.Cuts" user "Board Geometry/Outline")
		(27 "Margin" user)
		(31 "F.CrtYd" user "Package Geometry/Place Bound Top")
		(29 "B.CrtYd" user "Package Geometry/Place Bound Bottom")
		(35 "F.Fab" user "Ref Des/Assembly Top")
		(33 "B.Fab" user "Ref Des/Assembly Bottom")
	)
	(footprint ""
		(layer "F.Cu")
		(at 325.740776 -387.853428)
		(property "Reference" "C903"
			(at 0 0 0)
			(layer "F.SilkS")
			(hide yes)
			(effects
				(font
					(size 1.27 1.27)
				)
			)
		)
		(property "Value" ""
			(at 0 0 0)
			(layer "F.Fab")
			(effects
				(font
					(size 1.27 1.27)
				)
			)
		)
		(duplicate_pad_numbers_are_jumpers no)
		(fp_line
			(start -0.299974 -0.150114)
			(end 0.299974 -0.150114)
			(stroke
				(width 0.1)
				(type default)
			)
			(layer "F.Fab")
		)
		(fp_line
			(start -0.299974 0.150114)
			(end -0.299974 -0.150114)
			(stroke
				(width 0.1)
				(type default)
			)
			(layer "F.Fab")
		)
		(fp_line
			(start 0.299974 -0.150114)
			(end 0.299974 0.150114)
			(stroke
				(width 0.1)
				(type default)
			)
			(layer "F.Fab")
		)
		(fp_line
			(start 0.299974 0.150114)
			(end -0.299974 0.150114)
			(stroke
				(width 0.1)
				(type default)
			)
			(layer "F.Fab")
		)
		(pad "1" smd rect
			(at -0.2667 0)
			(size 0.3048 0.381)
			(layers "F.Cu" "F.Mask" "F.Paste")
			(net "P5E_CPU0_P0_TX_C_DP<15>")
		)
		(pad "2" smd rect
			(at 0.2667 0)
			(size 0.3048 0.381)
			(layers "F.Cu" "F.Mask" "F.Paste")
			(net "P5E_CPU0_P0_TX_DP<15>")
		)
	)
	(footprint ""
		(layer "F.Cu")
		(at 323.637148 -46.986698)
		(property "Reference" "R3679"
			(at 0 0 0)
			(layer "F.SilkS")
			(hide yes)
			(effects
				(font
					(size 1.27 1.27)
				)
			)
		)
		(property "Value" ""
			(at 0 0 0)
			(layer "F.Fab")
			(effects
				(font
					(size 1.27 1.27)
				)
			)
		)
		(duplicate_pad_numbers_are_jumpers no)
		(fp_line
			(start -0.7874 -0.4064)
			(end 0.7874 -0.4064)
			(stroke
				(width 0.1524)
				(type default)
			)
			(layer "F.SilkS")
		)
		(fp_line
			(start -0.7874 0.4064)
			(end -0.7874 -0.4064)
			(stroke
				(width 0.1524)
				(type default)
			)
			(layer "F.SilkS")
		)
		(fp_line
			(start 0.7874 -0.4064)
			(end 0.7874 0.4064)
			(stroke
				(width 0.1524)
				(type default)
			)
			(layer "F.SilkS")
		)
		(fp_line
			(start 0.7874 0.4064)
			(end -0.7874 0.4064)
			(stroke
				(width 0.1524)
				(type default)
			)
			(layer "F.SilkS")
		)
		(fp_line
			(start -0.67945 -0.305054)
			(end -0.12065 -0.305054)
			(stroke
				(width 0.1)
				(type default)
			)
			(layer "F.Fab")
		)
		(fp_line
			(start -0.67945 0.3048)
			(end -0.67945 -0.305054)
			(stroke
				(width 0.1)
				(type default)
			)
			(layer "F.Fab")
		)
		(fp_line
			(start -0.12065 -0.305054)
			(end -0.12065 -0.2794)
			(stroke
				(width 0.1)
				(type default)
			)
			(layer "F.Fab")
		)
		(fp_line
			(start -0.12065 -0.2794)
			(end 0.12065 -0.2794)
			(stroke
				(width 0.1)
				(type default)
			)
			(layer "F.Fab")
		)
		(fp_line
			(start -0.12065 0.2794)
			(end -0.12065 0.3048)
			(stroke
				(width 0.1)
				(type default)
			)
			(layer "F.Fab")
		)
		(fp_line
			(start -0.12065 0.3048)
			(end -0.67945 0.3048)
			(stroke
				(width 0.1)
				(type default)
			)
			(layer "F.Fab")
		)
		(fp_line
			(start 0.120396 0.2794)
			(end -0.12065 0.2794)
			(stroke
				(width 0.1)
				(type default)
			)
			(layer "F.Fab")
		)
		(fp_line
			(start 0.120396 0.3048)
			(end 0.120396 0.2794)
			(stroke
				(width 0.1)
				(type default)
			)
			(layer "F.Fab")
		)
		(fp_line
			(start 0.12065 -0.3048)
			(end 0.67945 -0.3048)
			(stroke
				(width 0.1)
				(type default)
			)
			(layer "F.Fab")
		)
		(fp_line
			(start 0.12065 -0.2794)
			(end 0.12065 -0.3048)
			(stroke
				(width 0.1)
				(type default)
			)
			(layer "F.Fab")
		)
		(fp_line
			(start 0.67945 -0.3048)
			(end 0.67945 0.3048)
			(stroke
				(width 0.1)
				(type default)
			)
			(layer "F.Fab")
		)
		(fp_line
			(start 0.67945 0.3048)
			(end 0.120396 0.3048)
			(stroke
				(width 0.1)
				(type default)
			)
			(layer "F.Fab")
		)
		(pad "1" smd rect
			(at -0.40005 0 180)
			(size 0.4572 0.508)
			(layers "F.Cu" "F.Mask" "F.Paste")
			(net "P12V_AUX_ADC")
		)
		(pad "2" smd rect
			(at 0.40005 0 180)
			(size 0.4572 0.508)
			(layers "F.Cu" "F.Mask" "F.Paste")
			(net "P12V_AUX_ADC_MAM")
		)
	)
	(footprint ""
		(layer "F.Cu")
		(at 49.849532 -343.716864 180)
		(property "Reference" "PC174"
			(at 0 0 180)
			(layer "F.SilkS")
			(hide yes)
			(effects
				(font
					(size 1.27 1.27)
				)
			)
		)
		(property "Value" ""
			(at 0 0 180)
			(layer "F.Fab")
			(effects
				(font
					(size 1.27 1.27)
				)
			)
		)
		(duplicate_pad_numbers_are_jumpers no)
		(fp_line
			(start 0.7874 0.4064)
			(end -0.7874 0.4064)
			(stroke
				(width 0.1524)
				(type default)
			)
			(layer "F.SilkS")
		)
		(fp_line
			(start 0.7874 -0.4064)
			(end 0.7874 0.4064)
			(stroke
				(width 0.1524)
				(type default)
			)
			(layer "F.SilkS")
		)
		(fp_line
			(start -0.7874 0.4064)
			(end -0.7874 -0.4064)
			(stroke
				(width 0.1524)
				(type default)
			)
			(layer "F.SilkS")
		)
		(fp_line
			(start -0.7874 -0.4064)
			(end 0.7874 -0.4064)
			(stroke
				(width 0.1524)
				(type default)
			)
			(layer "F.SilkS")
		)
		(fp_line
			(start 0.67945 0.3048)
			(end 0.120396 0.3048)
			(stroke
				(width 0.1)
				(type default)
			)
			(layer "F.Fab")
		)
		(fp_line
			(start 0.67945 -0.3048)
			(end 0.67945 0.3048)
			(stroke
				(width 0.1)
				(type default)
			)
			(layer "F.Fab")
		)
		(fp_line
			(start 0.12065 -0.2794)
			(end 0.12065 -0.3048)
			(stroke
				(width 0.1)
				(type default)
			)
			(layer "F.Fab")
		)
		(fp_line
			(start 0.12065 -0.3048)
			(end 0.67945 -0.3048)
			(stroke
				(width 0.1)
				(type default)
			)
			(layer "F.Fab")
		)
		(fp_line
			(start 0.120396 0.3048)
			(end 0.120396 0.2794)
			(stroke
				(width 0.1)
				(type default)
			)
			(layer "F.Fab")
		)
		(fp_line
			(start 0.120396 0.2794)
			(end -0.12065 0.2794)
			(stroke
				(width 0.1)
				(type default)
			)
			(layer "F.Fab")
		)
		(fp_line
			(start -0.12065 0.3048)
			(end -0.67945 0.3048)
			(stroke
				(width 0.1)
				(type default)
			)
			(layer "F.Fab")
		)
		(fp_line
			(start -0.12065 0.2794)
			(end -0.12065 0.3048)
			(stroke
				(width 0.1)
				(type default)
			)
			(layer "F.Fab")
		)
		(fp_line
			(start -0.12065 -0.2794)
			(end 0.12065 -0.2794)
			(stroke
				(width 0.1)
				(type default)
			)
			(layer "F.Fab")
		)
		(fp_line
			(start -0.12065 -0.305054)
			(end -0.12065 -0.2794)
			(stroke
				(width 0.1)
				(type default)
			)
			(layer "F.Fab")
		)
		(fp_line
			(start -0.67945 0.3048)
			(end -0.67945 -0.305054)
			(stroke
				(width 0.1)
				(type default)
			)
			(layer "F.Fab")
		)
		(fp_line
			(start -0.67945 -0.305054)
			(end -0.12065 -0.305054)
			(stroke
				(width 0.1)
				(type default)
			)
			(layer "F.Fab")
		)
		(pad "1" smd circle
			(at -0.40005 0 180)
			(size 0 0)
			(layers "F.Cu" "F.Mask" "F.Paste")
			(net "SW_PVDDIO_P1_SW1")
		)
		(pad "2" smd circle
			(at 0.40005 0 180)
			(size 0 0)
			(layers "F.Cu" "F.Mask" "F.Paste")
			(net "SW_PVDDIO_P1_SW1_RC")
		)
	)
)
